M48
INCH,TZ
T01C.008
T02C.01
T03C.012
T04C.014
T05C.01417
T06C.01456
T07C.016
T08C.02
T09C.02913
T010C.042
T011C.062
T012C.083
T013C.086
T014C.087
T015C.094
T016C.097
T017C.119
T018C.138
T019C.146
;EXTENTS: -106.644 -113.724 128.931 114.390 
;LEADER: 12 
;HEADER: 
;CODE  : ASCII 
;FILE  : 16316-1.rou for board 16316-1.brd
%
G90
F1
M16
G40
M30
